#ISCELL
  mstr_misc dns *
  *
#ISCELL
  mstr_misc prelim *
  *
#ISCELL
  mstr_symbols cad_note *
  *
#ISCELL
  mstr_symbols intel_corp_bpage *
  *
#ISCELL
  mstr_symbols gnd *
  page230_i1
#CELL
  mstr_discrete cap *
  page230_i10
#ISCELL
  mstr_symbols gnd *
  page230_i11
#CELL
  mstr_discrete cap *
  page230_i12
#CELL
  mstr_discrete res *
  page230_i13
#ISCELL
  mstr_symbols gnd *
  page230_i14
#ISCELL
  mstr_symbols gnd *
  page230_i15
#ISCELL
  mstr_symbols gnd *
  page230_i16
#CELL
  mstr_discrete cap *
  page230_i17
#ISCELL
  mstr_symbols gnd *
  page230_i18
#ISCELL
  mstr_symbols gnd *
  page230_i19
#CELL
  mstr_discrete cap *
  page230_i2
#CELL
  mstr_discrete cap *
  page230_i20
#CELL
  mstr_discrete res *
  page230_i21
#ISCELL
  mstr_symbols gnd *
  page230_i22
#CELL
  mstr_discrete cap *
  page230_i23
#CELL
  dev_discrete cap_a *
  page230_i24
#ISCELL
  mstr_symbols pvtt_klm *
  page230_i25
#ISCELL
  mstr_symbols p3v3 *
  page230_i26
#ISCELL
  mstr_symbols gnd *
  page230_i27
#ISCELL
  mstr_standard offpage *
  page230_i3
#CELL
  mstr_misc shunt *
  page230_i30
#CELL
  mstr_discrete res *
  page230_i32
#ISCELL
  mstr_standard offpage *
  page230_i33
#ISCELL
  mstr_symbols pvtt_klm *
  page230_i34
#CELL
  mstr_discrete cap *
  page230_i35
#CELL
  mstr_discrete cap *
  page230_i36
#CELL
  mstr_vreg mic5166 *
  page230_i37
#CELL
  mstr_discrete res *
  page230_i4
#CELL
  mstr_discrete cap *
  page230_i41
#CELL
  mstr_discrete cap *
  page230_i42
#CELL
  mstr_discrete cap *
  page230_i43
#CELL
  mstr_discrete res *
  page230_i5
#CELL
  mstr_discrete res *
  page230_i6
#ISCELL
  mstr_symbols p3v3 *
  page230_i7
#ISCELL
  mstr_symbols pvddq_klm *
  page230_i8
#ISCELL
  mstr_symbols gnd *
  page230_i9
